# BASEBOARD_FAB2 (Tioga Pass) — schematic netlist excerpt (pin names and nets, part order shuffled) for the footprints in the layout excerpt that follows; sources: Cadence DE-HDL packaged netlist, KiCad conversion of Wiwynn_Tioga_Pass_MB.brd

R4D32  RES  1.5K 1% CHIP  pkg 0402  page 201 : A = VR_PVCCIN_CPU0_AVINSEN ; B = GND
C4A8  CAP  1.0UF 16V 10% X6S  pkg 0402  page 230 : A = VR_PVTT_KLM_BIAS ; B = GND
C1D3  CAP_A  22.0UF 4V 20% X6S  pkg 0603V  page 208 : A = PVCCIN_CPU1 ; B = GND

(kicad_pcb
	(version 20260206)
	(generator "pcbnew")
	(generator_version "10.0")
	(general
		(thickness 1.6)
		(legacy_teardrops no)
	)
	(paper "A4")
	(title_block
		(title "Wiwynn_Tioga_Pass_MB.brd")
		(comment 1 "Tioga Pass / footprints 1000-1002 of 4770")
	)
	(layers
		(0 "F.Cu" signal "TOP")
		(4 "In1.Cu" signal "L2GND")
		(6 "In2.Cu" signal "L3")
		(8 "In3.Cu" signal "L4GND")
		(10 "In4.Cu" signal "L5")
		(12 "In5.Cu" signal "L6GND")
		(14 "In6.Cu" signal "L7VCC")
		(16 "In7.Cu" signal "L8VCC")
		(18 "In8.Cu" signal "L9GND")
		(20 "In9.Cu" signal "L10")
		(22 "In10.Cu" signal "L11GND")
		(24 "In11.Cu" signal "L12")
		(26 "In12.Cu" signal "L13GND")
		(2 "B.Cu" signal "BOTTOM")
		(9 "F.Adhes" user "F.Adhesive")
		(11 "B.Adhes" user "B.Adhesive")
		(13 "F.Paste" user "Package Geometry/Pastemask Top")
		(15 "B.Paste" user "Package Geometry/Pastemask Bottom")
		(5 "F.SilkS" user "Ref Des/Silkscreen Top")
		(7 "B.SilkS" user "Ref Des/Silkscreen Bottom")
		(1 "F.Mask" user "Board Geometry/Soldermask Top")
		(3 "B.Mask" user "Board Geometry/Soldermask Bottom")
		(17 "Dwgs.User" user "User.Drawings")
		(19 "Cmts.User" user "User.Comments")
		(21 "Eco1.User" user "User.Eco1")
		(23 "Eco2.User" user "User.Eco2")
		(25 "Edge.Cuts" user "Board Geometry/Outline")
		(27 "Margin" user)
		(31 "F.CrtYd" user "Package Geometry/Place Bound Top")
		(29 "B.CrtYd" user "Package Geometry/Place Bound Bottom")
		(35 "F.Fab" user "Ref Des/Assembly Top")
		(33 "B.Fab" user "Ref Des/Assembly Bottom")
	)
	(footprint ""
		(layer "F.Cu")
		(at 173.482 -146.939 90)
		(property "Reference" "C4A8"
			(at 0 0 90)
			(layer "F.SilkS")
			(hide yes)
			(effects
				(font
					(size 1.27 1.27)
				)
			)
		)
		(property "Value" ""
			(at 0 0 90)
			(layer "F.Fab")
			(effects
				(font
					(size 1.27 1.27)
				)
			)
		)
		(duplicate_pad_numbers_are_jumpers no)
		(fp_rect
			(start 0.3048 0.9906)
			(end -0.3048 -0.1016)
			(stroke
				(width 0)
				(type default)
			)
			(fill no)
			(layer "F.CrtYd")
		)
		(fp_line
			(start 0.3048 -0.1016)
			(end -0.3048 -0.1016)
			(stroke
				(width 0.1)
				(type default)
			)
			(layer "F.Fab")
		)
		(fp_line
			(start -0.3048 -0.1016)
			(end -0.3048 0.9906)
			(stroke
				(width 0.1)
				(type default)
			)
			(layer "F.Fab")
		)
		(fp_line
			(start 0.3048 0.9906)
			(end 0.3048 -0.1016)
			(stroke
				(width 0.1)
				(type default)
			)
			(layer "F.Fab")
		)
		(fp_line
			(start -0.3048 0.9906)
			(end 0.3048 0.9906)
			(stroke
				(width 0.1)
				(type default)
			)
			(layer "F.Fab")
		)
		(pad "1" smd rect
			(at 0 0 90)
			(size 0.508 0.508)
			(layers "F.Cu" "F.Mask" "F.Paste")
			(net "VR_PVTT_KLM_BIAS")
		)
		(pad "2" smd rect
			(at 0 0.889 90)
			(size 0.508 0.508)
			(layers "F.Cu" "F.Mask" "F.Paste")
			(net "GND")
		)
		(zone
			(layer "F.Cu")
			(hatch none 0.5)
			(connect_pads
				(clearance 0)
			)
			(min_thickness 0.25)
			(keepout
				(tracks not_allowed)
				(vias allowed)
				(pads allowed)
				(copperpour not_allowed)
				(footprints allowed)
			)
			(placement
				(enabled no)
				(sheetname "")
			)
			(fill
				(thermal_gap 0.5)
				(thermal_bridge_width 0.5)
				(island_removal_mode 0)
			)
			(polygon
				(pts
					(xy 174.117 -147.193) (xy 173.736 -147.193) (xy 173.736 -146.685) (xy 174.117 -146.685)
				)
			)
		)
		(zone
			(layer "F.Cu")
			(hatch none 0.5)
			(connect_pads
				(clearance 0)
			)
			(min_thickness 0.25)
			(keepout
				(tracks allowed)
				(vias not_allowed)
				(pads allowed)
				(copperpour not_allowed)
				(footprints allowed)
			)
			(placement
				(enabled no)
				(sheetname "")
			)
			(fill
				(thermal_gap 0.5)
				(thermal_bridge_width 0.5)
				(island_removal_mode 0)
			)
			(polygon
				(pts
					(xy 174.117 -147.193) (xy 173.736 -147.193) (xy 173.736 -146.685) (xy 174.117 -146.685)
				)
			)
		)
	)
	(footprint ""
		(layer "F.Cu")
		(at 49.4284 -86.67242)
		(property "Reference" "C1D3"
			(at 0 0 0)
			(layer "F.SilkS")
			(hide yes)
			(effects
				(font
					(size 1.27 1.27)
				)
			)
		)
		(property "Value" ""
			(at 0 0 0)
			(layer "F.Fab")
			(effects
				(font
					(size 1.27 1.27)
				)
			)
		)
		(duplicate_pad_numbers_are_jumpers no)
		(fp_poly
			(pts
				(xy -0.4953 -0.2032) (xy 0.4953 -0.2032) (xy 0.4953 1.6002) (xy -0.4953 1.6002)
			)
			(stroke
				(width 0)
				(type default)
			)
			(fill no)
			(layer "F.CrtYd")
		)
		(fp_line
			(start -0.4953 -0.2032)
			(end 0.4953 -0.2032)
			(stroke
				(width 0.1)
				(type default)
			)
			(layer "F.Fab")
		)
		(fp_line
			(start -0.4953 1.6002)
			(end -0.4953 -0.2032)
			(stroke
				(width 0.1)
				(type default)
			)
			(layer "F.Fab")
		)
		(fp_line
			(start 0.4953 -0.2032)
			(end 0.4953 1.6002)
			(stroke
				(width 0.1)
				(type default)
			)
			(layer "F.Fab")
		)
		(fp_line
			(start 0.4953 1.6002)
			(end -0.4953 1.6002)
			(stroke
				(width 0.1)
				(type default)
			)
			(layer "F.Fab")
		)
		(pad "1" smd rect
			(at 0 0)
			(size 0.762 0.889)
			(layers "F.Cu" "F.Mask" "F.Paste")
			(net "PVCCIN_CPU1")
		)
		(pad "2" smd rect
			(at 0 1.397)
			(size 0.762 0.889)
			(layers "F.Cu" "F.Mask" "F.Paste")
			(net "GND")
		)
		(zone
			(layer "F.Cu")
			(hatch none 0.5)
			(connect_pads
				(clearance 0)
			)
			(min_thickness 0.25)
			(keepout
				(tracks not_allowed)
				(vias allowed)
				(pads allowed)
				(copperpour not_allowed)
				(footprints allowed)
			)
			(placement
				(enabled no)
				(sheetname "")
			)
			(fill
				(thermal_gap 0.5)
				(thermal_bridge_width 0.5)
				(island_removal_mode 0)
			)
			(polygon
				(pts
					(xy 49.0474 -86.22792) (xy 49.8094 -86.22792) (xy 49.8094 -85.71992) (xy 49.0474 -85.71992)
				)
			)
		)
	)
	(footprint ""
		(layer "F.Cu")
		(at 183.0832 -76.3778 -90)
		(property "Reference" "R4D32"
			(at 0 0 270)
			(layer "F.SilkS")
			(hide yes)
			(effects
				(font
					(size 1.27 1.27)
				)
			)
		)
		(property "Value" ""
			(at 0 0 270)
			(layer "F.Fab")
			(effects
				(font
					(size 1.27 1.27)
				)
			)
		)
		(duplicate_pad_numbers_are_jumpers no)
		(fp_rect
			(start 0.2794 0.9906)
			(end -0.2794 -0.1016)
			(stroke
				(width 0)
				(type default)
			)
			(fill no)
			(layer "F.CrtYd")
		)
		(fp_line
			(start -0.2794 0.9906)
			(end 0.2794 0.9906)
			(stroke
				(width 0.1)
				(type default)
			)
			(layer "F.Fab")
		)
		(fp_line
			(start 0.2794 0.9906)
			(end 0.2794 -0.1016)
			(stroke
				(width 0.1)
				(type default)
			)
			(layer "F.Fab")
		)
		(fp_line
			(start -0.2794 -0.1016)
			(end -0.2794 0.9906)
			(stroke
				(width 0.1)
				(type default)
			)
			(layer "F.Fab")
		)
		(fp_line
			(start 0.2794 -0.1016)
			(end -0.2794 -0.1016)
			(stroke
				(width 0.1)
				(type default)
			)
			(layer "F.Fab")
		)
		(pad "1" smd rect
			(at 0 0 270)
			(size 0.508 0.508)
			(layers "F.Cu" "F.Mask" "F.Paste")
			(net "VR_PVCCIN_CPU0_AVINSEN")
		)
		(pad "2" smd rect
			(at 0 0.889 270)
			(size 0.508 0.508)
			(layers "F.Cu" "F.Mask" "F.Paste")
			(net "GND")
		)
		(zone
			(layer "F.Cu")
			(hatch none 0.5)
			(connect_pads
				(clearance 0)
			)
			(min_thickness 0.25)
			(keepout
				(tracks allowed)
				(vias not_allowed)
				(pads allowed)
				(copperpour not_allowed)
				(footprints allowed)
			)
			(placement
				(enabled no)
				(sheetname "")
			)
			(fill
				(thermal_gap 0.5)
				(thermal_bridge_width 0.5)
				(island_removal_mode 0)
			)
			(polygon
				(pts
					(xy 182.4482 -76.1238) (xy 182.8292 -76.1238) (xy 182.8292 -76.6318) (xy 182.4482 -76.6318)
				)
			)
		)
		(zone
			(layer "F.Cu")
			(hatch none 0.5)
			(connect_pads
				(clearance 0)
			)
			(min_thickness 0.25)
			(keepout
				(tracks not_allowed)
				(vias allowed)
				(pads allowed)
				(copperpour not_allowed)
				(footprints allowed)
			)
			(placement
				(enabled no)
				(sheetname "")
			)
			(fill
				(thermal_gap 0.5)
				(thermal_bridge_width 0.5)
				(island_removal_mode 0)
			)
			(polygon
				(pts
					(xy 182.4482 -76.1238) (xy 182.8292 -76.1238) (xy 182.8292 -76.6318) (xy 182.4482 -76.6318)
				)
			)
		)
	)
)
